(kicad_pcb
	(version 20260206)
	(generator "pcbnew")
	(generator_version "10.0")
	(general
		(thickness 1.6)
		(legacy_teardrops no)
	)
	(paper "A4")
	(title_block
		(title "peb — Lightning_PEB_BRD.brd")
		(comment 1 "Lightning (Wiwynn / Facebook NVMe JBOF) / footprints 484-490 of 2563")
	)
	(layers
		(0 "F.Cu" signal "TOP")
		(4 "In1.Cu" signal "L2GND")
		(6 "In2.Cu" signal "L3")
		(8 "In3.Cu" signal "L4VCC")
		(10 "In4.Cu" signal "L5VCC")
		(12 "In5.Cu" signal "L6")
		(14 "In6.Cu" signal "L7GND")
		(2 "B.Cu" signal "BOTTOM")
		(9 "F.Adhes" user "F.Adhesive")
		(11 "B.Adhes" user "B.Adhesive")
		(13 "F.Paste" user "Package Geometry/Pastemask Top")
		(15 "B.Paste" user "Package Geometry/Pastemask Bottom")
		(5 "F.SilkS" user "Ref Des/Silkscreen Top")
		(7 "B.SilkS" user "Ref Des/Silkscreen Bottom")
		(1 "F.Mask" user "Board Geometry/Soldermask Top")
		(3 "B.Mask" user "Board Geometry/Soldermask Bottom")
		(17 "Dwgs.User" user "User.Drawings")
		(19 "Cmts.User" user "User.Comments")
		(21 "Eco1.User" user "User.Eco1")
		(23 "Eco2.User" user "User.Eco2")
		(25 "Edge.Cuts" user "Board Geometry/Outline")
		(27 "Margin" user)
		(31 "F.CrtYd" user "Package Geometry/Place Bound Top")
		(29 "B.CrtYd" user "Package Geometry/Place Bound Bottom")
		(35 "F.Fab" user "Ref Des/Assembly Top")
		(33 "B.Fab" user "Ref Des/Assembly Bottom")
	)
	(footprint ""
		(layer "F.Cu")
		(at 18.8722 -194.1576 180)
		(property "Reference" "R9028"
			(at 0 0 180)
			(layer "F.SilkS")
			(hide yes)
			(effects
				(font
					(size 1.27 1.27)
				)
			)
		)
		(property "Value" "43K2R2F-L-GP"
			(at 0.064008 -3.993896 180)
			(unlocked yes)
			(layer "F.Fab")
			(hide yes)
			(effects
				(font
					(size 1.016 1.016)
					(thickness 0.1524)
				)
			)
		)
		(property "Device Type" "R402H16"
			(at 0.064008 -5.517896 180)
			(unlocked yes)
			(layer "F.Fab")
			(hide yes)
			(effects
				(font
					(size 1.016 1.016)
					(thickness 0.1524)
				)
			)
		)
		(duplicate_pad_numbers_are_jumpers no)
		(fp_line
			(start 0.508 -0.9398)
			(end -0.508 -0.9398)
			(stroke
				(width 0.1524)
				(type default)
			)
			(layer "F.SilkS")
		)
		(fp_line
			(start -0.508 -0.9398)
			(end -0.508 0.9398)
			(stroke
				(width 0.1524)
				(type default)
			)
			(layer "F.SilkS")
		)
		(fp_rect
			(start -0.508 0.9398)
			(end 0.508 -0.9398)
			(stroke
				(width 0)
				(type default)
			)
			(fill no)
			(layer "F.CrtYd")
		)
		(fp_rect
			(start -0.508 0.9398)
			(end 0.508 -0.9398)
			(stroke
				(width 0)
				(type default)
			)
			(fill no)
			(layer "F.Fab")
		)
		(pad "1" smd custom
			(at 0 -0.4445 180)
			(size 0.1397 0.1397)
			(layers "F.Cu" "F.Mask" "F.Paste")
			(net "MB0_PSET_R")
			(options
				(clearance outline)
				(anchor circle)
			)
			(primitives
				(gr_poly
					(pts
						(arc
							(start -0.1778 -0.2794)
							(mid -0.249642 -0.249642)
							(end -0.2794 -0.1778)
						)
						(arc
							(start -0.2794 0.1778)
							(mid -0.249642 0.249642)
							(end -0.1778 0.2794)
						)
						(arc
							(start 0.1778 0.2794)
							(mid 0.249642 0.249642)
							(end 0.2794 0.1778)
						)
						(arc
							(start 0.2794 -0.1778)
							(mid 0.249642 -0.249642)
							(end 0.1778 -0.2794)
						)
					)
					(width 0)
					(fill yes)
				)
			)
		)
		(pad "2" smd custom
			(at 0 0.4445 180)
			(size 0.1397 0.1397)
			(layers "F.Cu" "F.Mask" "F.Paste")
			(net "AGND_CURRENT_MON")
			(options
				(clearance outline)
				(anchor circle)
			)
			(primitives
				(gr_poly
					(pts
						(arc
							(start -0.1778 -0.2794)
							(mid -0.249642 -0.249642)
							(end -0.2794 -0.1778)
						)
						(arc
							(start -0.2794 0.1778)
							(mid -0.249642 0.249642)
							(end -0.1778 0.2794)
						)
						(arc
							(start 0.1778 0.2794)
							(mid 0.249642 0.249642)
							(end 0.2794 0.1778)
						)
						(arc
							(start 0.2794 -0.1778)
							(mid 0.249642 -0.249642)
							(end 0.1778 -0.2794)
						)
					)
					(width 0)
					(fill yes)
				)
			)
		)
	)
	(footprint ""
		(layer "F.Cu")
		(at 140.843 -41.4782 180)
		(property "Reference" "R761"
			(at 0 0 180)
			(layer "F.SilkS")
			(hide yes)
			(effects
				(font
					(size 1.27 1.27)
				)
			)
		)
		(property "Value" "0R2J-2-GP"
			(at 0.064008 -3.993896 180)
			(unlocked yes)
			(layer "F.Fab")
			(hide yes)
			(effects
				(font
					(size 1.016 1.016)
					(thickness 0.1524)
				)
			)
		)
		(property "Device Type" "R402H16"
			(at 0.064008 -5.517896 180)
			(unlocked yes)
			(layer "F.Fab")
			(hide yes)
			(effects
				(font
					(size 1.016 1.016)
					(thickness 0.1524)
				)
			)
		)
		(duplicate_pad_numbers_are_jumpers no)
		(fp_line
			(start 0.508 -0.9398)
			(end -0.508 -0.9398)
			(stroke
				(width 0.1524)
				(type default)
			)
			(layer "F.SilkS")
		)
		(fp_line
			(start -0.508 -0.9398)
			(end -0.508 0.9398)
			(stroke
				(width 0.1524)
				(type default)
			)
			(layer "F.SilkS")
		)
		(fp_rect
			(start -0.508 0.9398)
			(end 0.508 -0.9398)
			(stroke
				(width 0)
				(type default)
			)
			(fill no)
			(layer "F.CrtYd")
		)
		(fp_rect
			(start -0.508 0.9398)
			(end 0.508 -0.9398)
			(stroke
				(width 0)
				(type default)
			)
			(fill no)
			(layer "F.Fab")
		)
		(pad "1" smd custom
			(at 0 -0.4445 180)
			(size 0.1397 0.1397)
			(layers "F.Cu" "F.Mask" "F.Paste")
			(net "EJTAG_TMS_R")
			(options
				(clearance outline)
				(anchor circle)
			)
			(primitives
				(gr_poly
					(pts
						(arc
							(start -0.1778 -0.2794)
							(mid -0.249642 -0.249642)
							(end -0.2794 -0.1778)
						)
						(arc
							(start -0.2794 0.1778)
							(mid -0.249642 0.249642)
							(end -0.1778 0.2794)
						)
						(arc
							(start 0.1778 0.2794)
							(mid 0.249642 0.249642)
							(end 0.2794 0.1778)
						)
						(arc
							(start 0.2794 -0.1778)
							(mid 0.249642 -0.249642)
							(end 0.1778 -0.2794)
						)
					)
					(width 0)
					(fill yes)
				)
			)
		)
		(pad "2" smd custom
			(at 0 0.4445 180)
			(size 0.1397 0.1397)
			(layers "F.Cu" "F.Mask" "F.Paste")
			(net "EJTAG_TMS")
			(options
				(clearance outline)
				(anchor circle)
			)
			(primitives
				(gr_poly
					(pts
						(arc
							(start -0.1778 -0.2794)
							(mid -0.249642 -0.249642)
							(end -0.2794 -0.1778)
						)
						(arc
							(start -0.2794 0.1778)
							(mid -0.249642 0.249642)
							(end -0.1778 0.2794)
						)
						(arc
							(start 0.1778 0.2794)
							(mid 0.249642 0.249642)
							(end 0.2794 0.1778)
						)
						(arc
							(start 0.2794 -0.1778)
							(mid 0.249642 -0.249642)
							(end 0.1778 -0.2794)
						)
					)
					(width 0)
					(fill yes)
				)
			)
		)
	)
	(footprint ""
		(layer "F.Cu")
		(at 27.6352 -53.8988 90)
		(property "Reference" "R539"
			(at 0 0 90)
			(layer "F.SilkS")
			(hide yes)
			(effects
				(font
					(size 1.27 1.27)
				)
			)
		)
		(property "Value" "0R2J-2-GP"
			(at 0.064008 -3.993896 90)
			(unlocked yes)
			(layer "F.Fab")
			(hide yes)
			(effects
				(font
					(size 1.016 1.016)
					(thickness 0.1524)
				)
			)
		)
		(property "Device Type" "R402H16"
			(at 0.064008 -5.517896 90)
			(unlocked yes)
			(layer "F.Fab")
			(hide yes)
			(effects
				(font
					(size 1.016 1.016)
					(thickness 0.1524)
				)
			)
		)
		(duplicate_pad_numbers_are_jumpers no)
		(fp_line
			(start 0.508 -0.9398)
			(end -0.508 -0.9398)
			(stroke
				(width 0.1524)
				(type default)
			)
			(layer "F.SilkS")
		)
		(fp_line
			(start -0.508 -0.9398)
			(end -0.508 0.9398)
			(stroke
				(width 0.1524)
				(type default)
			)
			(layer "F.SilkS")
		)
		(fp_rect
			(start -0.508 0.9398)
			(end 0.508 -0.9398)
			(stroke
				(width 0)
				(type default)
			)
			(fill no)
			(layer "F.CrtYd")
		)
		(fp_rect
			(start -0.508 0.9398)
			(end 0.508 -0.9398)
			(stroke
				(width 0)
				(type default)
			)
			(fill no)
			(layer "F.Fab")
		)
		(pad "1" smd custom
			(at 0 -0.4445 90)
			(size 0.1397 0.1397)
			(layers "F.Cu" "F.Mask" "F.Paste")
			(net "LED_MDI0_1G_N")
			(options
				(clearance outline)
				(anchor circle)
			)
			(primitives
				(gr_poly
					(pts
						(arc
							(start -0.1778 -0.2794)
							(mid -0.249642 -0.249642)
							(end -0.2794 -0.1778)
						)
						(arc
							(start -0.2794 0.1778)
							(mid -0.249642 0.249642)
							(end -0.1778 0.2794)
						)
						(arc
							(start 0.1778 0.2794)
							(mid 0.249642 0.249642)
							(end 0.2794 0.1778)
						)
						(arc
							(start 0.2794 -0.1778)
							(mid 0.249642 -0.249642)
							(end 0.1778 -0.2794)
						)
					)
					(width 0)
					(fill yes)
				)
			)
		)
		(pad "2" smd custom
			(at 0 0.4445 90)
			(size 0.1397 0.1397)
			(layers "F.Cu" "F.Mask" "F.Paste")
			(net "LED_MDI0_1G_N_R")
			(options
				(clearance outline)
				(anchor circle)
			)
			(primitives
				(gr_poly
					(pts
						(arc
							(start -0.1778 -0.2794)
							(mid -0.249642 -0.249642)
							(end -0.2794 -0.1778)
						)
						(arc
							(start -0.2794 0.1778)
							(mid -0.249642 0.249642)
							(end -0.1778 0.2794)
						)
						(arc
							(start 0.1778 0.2794)
							(mid 0.249642 0.249642)
							(end 0.2794 0.1778)
						)
						(arc
							(start 0.2794 -0.1778)
							(mid 0.249642 -0.249642)
							(end 0.1778 -0.2794)
						)
					)
					(width 0)
					(fill yes)
				)
			)
		)
	)
	(footprint ""
		(layer "F.Cu")
		(at 72.5678 -160.0708 -90)
		(property "Reference" "PR23"
			(at 0 0 270)
			(layer "F.SilkS")
			(hide yes)
			(effects
				(font
					(size 1.27 1.27)
				)
			)
		)
		(property "Value" "0R3J-0-U-GP"
			(at -0.0254 -2.5146 270)
			(unlocked yes)
			(layer "F.Fab")
			(hide yes)
			(effects
				(font
					(size 1.016 1.016)
					(thickness 0.1524)
				)
			)
		)
		(property "Device Type" "R603H22"
			(at -0.0254 -4.0386 270)
			(unlocked yes)
			(layer "F.Fab")
			(hide yes)
			(effects
				(font
					(size 1.016 1.016)
					(thickness 0.1524)
				)
			)
		)
		(duplicate_pad_numbers_are_jumpers no)
		(fp_line
			(start -0.4826 0)
			(end -0.2032 0)
			(stroke
				(width 0.2032)
				(type default)
			)
			(layer "F.SilkS")
		)
		(fp_line
			(start 0.2032 0)
			(end 0.4826 0)
			(stroke
				(width 0.2032)
				(type default)
			)
			(layer "F.SilkS")
		)
		(fp_rect
			(start -0.5842 1.3335)
			(end 0.5842 -1.3335)
			(stroke
				(width 0)
				(type default)
			)
			(fill no)
			(layer "F.CrtYd")
		)
		(fp_rect
			(start -0.5842 1.3335)
			(end 0.5842 -1.3335)
			(stroke
				(width 0)
				(type default)
			)
			(fill no)
			(layer "F.Fab")
		)
		(pad "1" smd custom
			(at 0 -0.762 270)
			(size 0.2159 0.2159)
			(layers "F.Cu" "F.Mask" "F.Paste")
			(net "P3V3_STBY")
			(options
				(clearance outline)
				(anchor circle)
			)
			(primitives
				(gr_poly
					(pts
						(arc
							(start -0.3302 -0.4318)
							(mid -0.402042 -0.402042)
							(end -0.4318 -0.3302)
						)
						(arc
							(start -0.4318 0.3302)
							(mid -0.402042 0.402042)
							(end -0.3302 0.4318)
						)
						(arc
							(start 0.3302 0.4318)
							(mid 0.402042 0.402042)
							(end 0.4318 0.3302)
						)
						(arc
							(start 0.4318 -0.3302)
							(mid 0.402042 -0.402042)
							(end 0.3302 -0.4318)
						)
					)
					(width 0)
					(fill yes)
				)
			)
		)
		(pad "2" smd custom
			(at 0 0.762 270)
			(size 0.2159 0.2159)
			(layers "F.Cu" "F.Mask" "F.Paste")
			(net "VR_P1V538_STBY_IN")
			(options
				(clearance outline)
				(anchor circle)
			)
			(primitives
				(gr_poly
					(pts
						(arc
							(start -0.3302 -0.4318)
							(mid -0.402042 -0.402042)
							(end -0.4318 -0.3302)
						)
						(arc
							(start -0.4318 0.3302)
							(mid -0.402042 0.402042)
							(end -0.3302 0.4318)
						)
						(arc
							(start 0.3302 0.4318)
							(mid 0.402042 0.402042)
							(end 0.4318 0.3302)
						)
						(arc
							(start 0.4318 -0.3302)
							(mid 0.402042 -0.402042)
							(end 0.3302 -0.4318)
						)
					)
					(width 0)
					(fill yes)
				)
			)
		)
	)
	(footprint ""
		(layer "F.Cu")
		(at 50.292 -185.293 90)
		(property "Reference" "R897"
			(at 0 0 90)
			(layer "F.SilkS")
			(hide yes)
			(effects
				(font
					(size 1.27 1.27)
				)
			)
		)
		(property "Value" "4K7R2J-2-GP"
			(at 0.064008 -3.993896 90)
			(unlocked yes)
			(layer "F.Fab")
			(hide yes)
			(effects
				(font
					(size 1.016 1.016)
					(thickness 0.1524)
				)
			)
		)
		(property "Device Type" "R402H16"
			(at 0.064008 -5.517896 90)
			(unlocked yes)
			(layer "F.Fab")
			(hide yes)
			(effects
				(font
					(size 1.016 1.016)
					(thickness 0.1524)
				)
			)
		)
		(duplicate_pad_numbers_are_jumpers no)
		(fp_line
			(start 0.508 -0.9398)
			(end -0.508 -0.9398)
			(stroke
				(width 0.1524)
				(type default)
			)
			(layer "F.SilkS")
		)
		(fp_line
			(start -0.508 -0.9398)
			(end -0.508 0.9398)
			(stroke
				(width 0.1524)
				(type default)
			)
			(layer "F.SilkS")
		)
		(fp_rect
			(start -0.508 0.9398)
			(end 0.508 -0.9398)
			(stroke
				(width 0)
				(type default)
			)
			(fill no)
			(layer "F.CrtYd")
		)
		(fp_rect
			(start -0.508 0.9398)
			(end 0.508 -0.9398)
			(stroke
				(width 0)
				(type default)
			)
			(fill no)
			(layer "F.Fab")
		)
		(pad "1" smd custom
			(at 0 -0.4445 90)
			(size 0.1397 0.1397)
			(layers "F.Cu" "F.Mask" "F.Paste")
			(net "P3V3_STBY")
			(options
				(clearance outline)
				(anchor circle)
			)
			(primitives
				(gr_poly
					(pts
						(arc
							(start -0.1778 -0.2794)
							(mid -0.249642 -0.249642)
							(end -0.2794 -0.1778)
						)
						(arc
							(start -0.2794 0.1778)
							(mid -0.249642 0.249642)
							(end -0.1778 0.2794)
						)
						(arc
							(start 0.1778 0.2794)
							(mid 0.249642 0.249642)
							(end 0.2794 0.1778)
						)
						(arc
							(start 0.2794 -0.1778)
							(mid 0.249642 -0.249642)
							(end 0.1778 -0.2794)
						)
					)
					(width 0)
					(fill yes)
				)
			)
		)
		(pad "2" smd custom
			(at 0 0.4445 90)
			(size 0.1397 0.1397)
			(layers "F.Cu" "F.Mask" "F.Paste")
			(net "BUF_I2C8_CLKBUF1_SDA_R")
			(options
				(clearance outline)
				(anchor circle)
			)
			(primitives
				(gr_poly
					(pts
						(arc
							(start -0.1778 -0.2794)
							(mid -0.249642 -0.249642)
							(end -0.2794 -0.1778)
						)
						(arc
							(start -0.2794 0.1778)
							(mid -0.249642 0.249642)
							(end -0.1778 0.2794)
						)
						(arc
							(start 0.1778 0.2794)
							(mid 0.249642 0.249642)
							(end 0.2794 0.1778)
						)
						(arc
							(start 0.2794 -0.1778)
							(mid 0.249642 -0.249642)
							(end 0.1778 -0.2794)
						)
					)
					(width 0)
					(fill yes)
				)
			)
		)
	)
	(footprint ""
		(layer "F.Cu")
		(at 161.544 -85.2424)
		(property "Reference" "R3102"
			(at 0 0 0)
			(layer "F.SilkS")
			(hide yes)
			(effects
				(font
					(size 1.27 1.27)
				)
			)
		)
		(property "Value" "27R2F-GP"
			(at 0.064008 -3.993896 0)
			(unlocked yes)
			(layer "F.Fab")
			(hide yes)
			(effects
				(font
					(size 1.016 1.016)
					(thickness 0.1524)
				)
			)
		)
		(property "Device Type" "R402H16"
			(at 0.064008 -5.517896 0)
			(unlocked yes)
			(layer "F.Fab")
			(hide yes)
			(effects
				(font
					(size 1.016 1.016)
					(thickness 0.1524)
				)
			)
		)
		(duplicate_pad_numbers_are_jumpers no)
		(fp_line
			(start -0.508 -0.9398)
			(end -0.508 0.9398)
			(stroke
				(width 0.1524)
				(type default)
			)
			(layer "F.SilkS")
		)
		(fp_line
			(start 0.508 -0.9398)
			(end -0.508 -0.9398)
			(stroke
				(width 0.1524)
				(type default)
			)
			(layer "F.SilkS")
		)
		(fp_rect
			(start -0.508 0.9398)
			(end 0.508 -0.9398)
			(stroke
				(width 0)
				(type default)
			)
			(fill no)
			(layer "F.CrtYd")
		)
		(fp_rect
			(start -0.508 0.9398)
			(end 0.508 -0.9398)
			(stroke
				(width 0)
				(type default)
			)
			(fill no)
			(layer "F.Fab")
		)
		(pad "1" smd custom
			(at 0 -0.4445)
			(size 0.1397 0.1397)
			(layers "F.Cu" "F.Mask" "F.Paste")
			(net "PCIE_REFCLK_D_P_R")
			(options
				(clearance outline)
				(anchor circle)
			)
			(primitives
				(gr_poly
					(pts
						(arc
							(start -0.1778 -0.2794)
							(mid -0.249642 -0.249642)
							(end -0.2794 -0.1778)
						)
						(arc
							(start -0.2794 0.1778)
							(mid -0.249642 0.249642)
							(end -0.1778 0.2794)
						)
						(arc
							(start 0.1778 0.2794)
							(mid 0.249642 0.249642)
							(end 0.2794 0.1778)
						)
						(arc
							(start 0.2794 -0.1778)
							(mid 0.249642 -0.249642)
							(end 0.1778 -0.2794)
						)
					)
					(width 0)
					(fill yes)
				)
			)
		)
		(pad "2" smd custom
			(at 0 0.4445)
			(size 0.1397 0.1397)
			(layers "F.Cu" "F.Mask" "F.Paste")
			(net "PCIE_REFCLK_D_P")
			(options
				(clearance outline)
				(anchor circle)
			)
			(primitives
				(gr_poly
					(pts
						(arc
							(start -0.1778 -0.2794)
							(mid -0.249642 -0.249642)
							(end -0.2794 -0.1778)
						)
						(arc
							(start -0.2794 0.1778)
							(mid -0.249642 0.249642)
							(end -0.1778 0.2794)
						)
						(arc
							(start 0.1778 0.2794)
							(mid 0.249642 0.249642)
							(end 0.2794 0.1778)
						)
						(arc
							(start 0.2794 -0.1778)
							(mid 0.249642 -0.249642)
							(end 0.1778 -0.2794)
						)
					)
					(width 0)
					(fill yes)
				)
			)
		)
	)
	(footprint ""
		(layer "F.Cu")
		(at 52.7558 -113.284 -90)
		(property "Reference" "R441"
			(at 0 0 270)
			(layer "F.SilkS")
			(hide yes)
			(effects
				(font
					(size 1.27 1.27)
				)
			)
		)
		(property "Value" "4K7R2F-GP"
			(at 0.064008 -3.993896 270)
			(unlocked yes)
			(layer "F.Fab")
			(hide yes)
			(effects
				(font
					(size 1.016 1.016)
					(thickness 0.1524)
				)
			)
		)
		(property "Device Type" "R402H16"
			(at 0.064008 -5.517896 270)
			(unlocked yes)
			(layer "F.Fab")
			(hide yes)
			(effects
				(font
					(size 1.016 1.016)
					(thickness 0.1524)
				)
			)
		)
		(duplicate_pad_numbers_are_jumpers no)
		(fp_line
			(start -0.508 -0.9398)
			(end -0.508 0.9398)
			(stroke
				(width 0.1524)
				(type default)
			)
			(layer "F.SilkS")
		)
		(fp_line
			(start 0.508 -0.9398)
			(end -0.508 -0.9398)
			(stroke
				(width 0.1524)
				(type default)
			)
			(layer "F.SilkS")
		)
		(fp_rect
			(start -0.508 0.9398)
			(end 0.508 -0.9398)
			(stroke
				(width 0)
				(type default)
			)
			(fill no)
			(layer "F.CrtYd")
		)
		(fp_rect
			(start -0.508 0.9398)
			(end 0.508 -0.9398)
			(stroke
				(width 0)
				(type default)
			)
			(fill no)
			(layer "F.Fab")
		)
		(pad "1" smd custom
			(at 0 -0.4445 270)
			(size 0.1397 0.1397)
			(layers "F.Cu" "F.Mask" "F.Paste")
			(net "BMC_I2C13_MINI7_SDA_S")
			(options
				(clearance outline)
				(anchor circle)
			)
			(primitives
				(gr_poly
					(pts
						(arc
							(start -0.1778 -0.2794)
							(mid -0.249642 -0.249642)
							(end -0.2794 -0.1778)
						)
						(arc
							(start -0.2794 0.1778)
							(mid -0.249642 0.249642)
							(end -0.1778 0.2794)
						)
						(arc
							(start 0.1778 0.2794)
							(mid 0.249642 0.249642)
							(end 0.2794 0.1778)
						)
						(arc
							(start 0.2794 -0.1778)
							(mid 0.249642 -0.249642)
							(end 0.1778 -0.2794)
						)
					)
					(width 0)
					(fill yes)
				)
			)
		)
		(pad "2" smd custom
			(at 0 0.4445 270)
			(size 0.1397 0.1397)
			(layers "F.Cu" "F.Mask" "F.Paste")
			(net "P3V3_STBY")
			(options
				(clearance outline)
				(anchor circle)
			)
			(primitives
				(gr_poly
					(pts
						(arc
							(start -0.1778 -0.2794)
							(mid -0.249642 -0.249642)
							(end -0.2794 -0.1778)
						)
						(arc
							(start -0.2794 0.1778)
							(mid -0.249642 0.249642)
							(end -0.1778 0.2794)
						)
						(arc
							(start 0.1778 0.2794)
							(mid 0.249642 0.249642)
							(end 0.2794 0.1778)
						)
						(arc
							(start 0.2794 -0.1778)
							(mid 0.249642 -0.249642)
							(end 0.1778 -0.2794)
						)
					)
					(width 0)
					(fill yes)
				)
			)
		)
	)
)
